# T6G (Grand Teton) — schematic netlist excerpt (pin names and nets, part order shuffled) for the footprints in the layout excerpt that follows; sources: Cadence DE-HDL packaged netlist, KiCad conversion of 04192023_DAF0TMB3IC0_F0TG_MB_C_brd_V02_OCP.brd

PC6519  Q_CAP  0.1UF 25V 10% X6S  pkg C0402  page 361 : A = P12V_AUX ; B = GND
C6028  Q_CAP  470PF 50V 10% X7R  pkg 0402  page 176 : A = P5V_AUX ; B = GND

(kicad_pcb
	(version 20260206)
	(generator "pcbnew")
	(generator_version "10.0")
	(general
		(thickness 1.6)
		(legacy_teardrops no)
	)
	(paper "A4")
	(title_block
		(title "04192023_DAF0TMB3IC0_F0TG_MB_C_brd_V02_OCP.brd")
		(comment 1 "Grand Teton / footprints 844-845 of 8354")
	)
	(layers
		(0 "F.Cu" signal "TOP")
		(4 "In1.Cu" signal "GND")
		(6 "In2.Cu" signal "IN1")
		(8 "In3.Cu" signal "GND1")
		(10 "In4.Cu" signal "IN2")
		(12 "In5.Cu" signal "GND2")
		(14 "In6.Cu" signal "IN3")
		(16 "In7.Cu" signal "GND3")
		(18 "In8.Cu" signal "VCC")
		(20 "In9.Cu" signal "VCC1")
		(22 "In10.Cu" signal "GND4")
		(24 "In11.Cu" signal "IN4")
		(26 "In12.Cu" signal "GND5")
		(28 "In13.Cu" signal "IN5")
		(30 "In14.Cu" signal "GND6")
		(32 "In15.Cu" signal "IN6")
		(34 "In16.Cu" signal "GND7")
		(2 "B.Cu" signal "BOTTOM")
		(9 "F.Adhes" user "F.Adhesive")
		(11 "B.Adhes" user "B.Adhesive")
		(13 "F.Paste" user "Package Geometry/Pastemask Top")
		(15 "B.Paste" user "Package Geometry/Pastemask Bottom")
		(5 "F.SilkS" user "Ref Des/Silkscreen Top")
		(7 "B.SilkS" user "Ref Des/Silkscreen Bottom")
		(1 "F.Mask" user "Board Geometry/Soldermask Top")
		(3 "B.Mask" user "Board Geometry/Soldermask Bottom")
		(17 "Dwgs.User" user "User.Drawings")
		(19 "Cmts.User" user "User.Comments")
		(21 "Eco1.User" user "User.Eco1")
		(23 "Eco2.User" user "User.Eco2")
		(25 "Edge.Cuts" user "Board Geometry/Outline")
		(27 "Margin" user)
		(31 "F.CrtYd" user "Package Geometry/Place Bound Top")
		(29 "B.CrtYd" user "Package Geometry/Place Bound Bottom")
		(35 "F.Fab" user "Ref Des/Assembly Top")
		(33 "B.Fab" user "Ref Des/Assembly Bottom")
	)
	(footprint ""
		(layer "F.Cu")
		(at 225.420428 -268.232382)
		(property "Reference" "PC6519"
			(at 0 0 0)
			(layer "F.SilkS")
			(hide yes)
			(effects
				(font
					(size 1.27 1.27)
				)
			)
		)
		(property "Value" ""
			(at 0 0 0)
			(layer "F.Fab")
			(effects
				(font
					(size 1.27 1.27)
				)
			)
		)
		(duplicate_pad_numbers_are_jumpers no)
		(fp_line
			(start -0.7874 -0.4064)
			(end 0.7874 -0.4064)
			(stroke
				(width 0.1524)
				(type default)
			)
			(layer "F.SilkS")
		)
		(fp_line
			(start -0.7874 0.4064)
			(end -0.7874 -0.4064)
			(stroke
				(width 0.1524)
				(type default)
			)
			(layer "F.SilkS")
		)
		(fp_line
			(start 0.7874 -0.4064)
			(end 0.7874 0.4064)
			(stroke
				(width 0.1524)
				(type default)
			)
			(layer "F.SilkS")
		)
		(fp_line
			(start 0.7874 0.4064)
			(end -0.7874 0.4064)
			(stroke
				(width 0.1524)
				(type default)
			)
			(layer "F.SilkS")
		)
		(fp_line
			(start -0.67945 -0.305054)
			(end -0.12065 -0.305054)
			(stroke
				(width 0.1)
				(type default)
			)
			(layer "F.Fab")
		)
		(fp_line
			(start -0.67945 0.3048)
			(end -0.67945 -0.305054)
			(stroke
				(width 0.1)
				(type default)
			)
			(layer "F.Fab")
		)
		(fp_line
			(start -0.12065 -0.305054)
			(end -0.12065 -0.2794)
			(stroke
				(width 0.1)
				(type default)
			)
			(layer "F.Fab")
		)
		(fp_line
			(start -0.12065 -0.2794)
			(end 0.12065 -0.2794)
			(stroke
				(width 0.1)
				(type default)
			)
			(layer "F.Fab")
		)
		(fp_line
			(start -0.12065 0.2794)
			(end -0.12065 0.3048)
			(stroke
				(width 0.1)
				(type default)
			)
			(layer "F.Fab")
		)
		(fp_line
			(start -0.12065 0.3048)
			(end -0.67945 0.3048)
			(stroke
				(width 0.1)
				(type default)
			)
			(layer "F.Fab")
		)
		(fp_line
			(start 0.120396 0.2794)
			(end -0.12065 0.2794)
			(stroke
				(width 0.1)
				(type default)
			)
			(layer "F.Fab")
		)
		(fp_line
			(start 0.120396 0.3048)
			(end 0.120396 0.2794)
			(stroke
				(width 0.1)
				(type default)
			)
			(layer "F.Fab")
		)
		(fp_line
			(start 0.12065 -0.3048)
			(end 0.67945 -0.3048)
			(stroke
				(width 0.1)
				(type default)
			)
			(layer "F.Fab")
		)
		(fp_line
			(start 0.12065 -0.2794)
			(end 0.12065 -0.3048)
			(stroke
				(width 0.1)
				(type default)
			)
			(layer "F.Fab")
		)
		(fp_line
			(start 0.67945 -0.3048)
			(end 0.67945 0.3048)
			(stroke
				(width 0.1)
				(type default)
			)
			(layer "F.Fab")
		)
		(fp_line
			(start 0.67945 0.3048)
			(end 0.120396 0.3048)
			(stroke
				(width 0.1)
				(type default)
			)
			(layer "F.Fab")
		)
		(pad "1" smd circle
			(at -0.40005 0)
			(size 0 0)
			(layers "F.Cu" "F.Mask" "F.Paste")
			(net "P12V_AUX")
		)
		(pad "2" smd circle
			(at 0.40005 0)
			(size 0 0)
			(layers "F.Cu" "F.Mask" "F.Paste")
			(net "GND")
		)
	)
	(footprint ""
		(layer "F.Cu")
		(at 141.624812 -49.159414)
		(property "Reference" "C6028"
			(at 0 0 0)
			(layer "F.SilkS")
			(hide yes)
			(effects
				(font
					(size 1.27 1.27)
				)
			)
		)
		(property "Value" ""
			(at 0 0 0)
			(layer "F.Fab")
			(effects
				(font
					(size 1.27 1.27)
				)
			)
		)
		(duplicate_pad_numbers_are_jumpers no)
		(fp_line
			(start -0.7874 -0.4064)
			(end 0.7874 -0.4064)
			(stroke
				(width 0.1524)
				(type default)
			)
			(layer "F.SilkS")
		)
		(fp_line
			(start -0.7874 0.4064)
			(end -0.7874 -0.4064)
			(stroke
				(width 0.1524)
				(type default)
			)
			(layer "F.SilkS")
		)
		(fp_line
			(start 0.7874 -0.4064)
			(end 0.7874 0.4064)
			(stroke
				(width 0.1524)
				(type default)
			)
			(layer "F.SilkS")
		)
		(fp_line
			(start 0.7874 0.4064)
			(end -0.7874 0.4064)
			(stroke
				(width 0.1524)
				(type default)
			)
			(layer "F.SilkS")
		)
		(fp_line
			(start -0.67945 -0.305054)
			(end -0.12065 -0.305054)
			(stroke
				(width 0.1)
				(type default)
			)
			(layer "F.Fab")
		)
		(fp_line
			(start -0.67945 0.3048)
			(end -0.67945 -0.305054)
			(stroke
				(width 0.1)
				(type default)
			)
			(layer "F.Fab")
		)
		(fp_line
			(start -0.12065 -0.305054)
			(end -0.12065 -0.2794)
			(stroke
				(width 0.1)
				(type default)
			)
			(layer "F.Fab")
		)
		(fp_line
			(start -0.12065 -0.2794)
			(end 0.12065 -0.2794)
			(stroke
				(width 0.1)
				(type default)
			)
			(layer "F.Fab")
		)
		(fp_line
			(start -0.12065 0.2794)
			(end -0.12065 0.3048)
			(stroke
				(width 0.1)
				(type default)
			)
			(layer "F.Fab")
		)
		(fp_line
			(start -0.12065 0.3048)
			(end -0.67945 0.3048)
			(stroke
				(width 0.1)
				(type default)
			)
			(layer "F.Fab")
		)
		(fp_line
			(start 0.120396 0.2794)
			(end -0.12065 0.2794)
			(stroke
				(width 0.1)
				(type default)
			)
			(layer "F.Fab")
		)
		(fp_line
			(start 0.120396 0.3048)
			(end 0.120396 0.2794)
			(stroke
				(width 0.1)
				(type default)
			)
			(layer "F.Fab")
		)
		(fp_line
			(start 0.12065 -0.3048)
			(end 0.67945 -0.3048)
			(stroke
				(width 0.1)
				(type default)
			)
			(layer "F.Fab")
		)
		(fp_line
			(start 0.12065 -0.2794)
			(end 0.12065 -0.3048)
			(stroke
				(width 0.1)
				(type default)
			)
			(layer "F.Fab")
		)
		(fp_line
			(start 0.67945 -0.3048)
			(end 0.67945 0.3048)
			(stroke
				(width 0.1)
				(type default)
			)
			(layer "F.Fab")
		)
		(fp_line
			(start 0.67945 0.3048)
			(end 0.120396 0.3048)
			(stroke
				(width 0.1)
				(type default)
			)
			(layer "F.Fab")
		)
		(pad "1" smd circle
			(at -0.40005 0)
			(size 0 0)
			(layers "F.Cu" "F.Mask" "F.Paste")
			(net "P5V_AUX")
		)
		(pad "2" smd circle
			(at 0.40005 0)
			(size 0 0)
			(layers "F.Cu" "F.Mask" "F.Paste")
			(net "GND")
		)
	)
)
